#ISCELL
  mstr_misc dns *
  *
#ISCELL
  pure_quanta quanta_title_block_c *
  *
#ISCELL
  pure_quanta_power universal_gnd *
  page386_i1
#ISCELL
  pure_quanta_power universal_gnd *
  page386_i10
#ISCELL
  pure_quanta_power p1v0 *
  page386_i11
#ISCELL
  pure_quanta_power universal_gnd *
  page386_i12
#CELL
  pure_quanta q_res *
  page386_i13
#ISCELL
  pure_quanta_power universal_gnd *
  page386_i14
#CELL
  pure_quanta q_res *
  page386_i15
#ISCELL
  pure_quanta_power universal_gnd *
  page386_i16
#CELL
  pure_quanta pt5161lrs *
  page386_i17
#CELL
  pure_quanta q_res *
  page386_i18
#CELL
  pure_quanta q_res *
  page386_i19
#CELL
  pure_quanta pt5161lrs *
  page386_i3
#ISCELL
  pure_quanta_power p1v0 *
  page386_i5
#ISCELL
  pure_quanta_power p1v0 *
  page386_i6
#ISCELL
  pure_quanta_power p1v0 *
  page386_i7
#ISCELL
  pure_quanta_power vcc_core *
  page386_i8
#ISCELL
  pure_quanta_power vcc_core *
  page386_i9
